# T6G (Grand Teton) — schematic netlist excerpt (pin names and nets, part order shuffled) for the footprints in the layout excerpt that follows; sources: Cadence DE-HDL packaged netlist, KiCad conversion of 04192023_DAF0TMB3IC0_F0TG_MB_C_brd_V02_OCP.brd

PC850  Q_CAP  22UF 4V 20% X6S  pkg C0805  page 269 : A = P1V8_AUX ; B = GND
PR6  Q_RES  10K 1% CHIP  pkg 0402LF  page 224 : A = PVDD11_S3_P1_VMON ; B = GND
R3942  Q_RES  0 5% EMPTY  pkg 0402LF  page 257 : A = P12V_E1S_0_ISENSE_MPS_TIC ; B = P12V_E1S_0_ISENSE_TIC

(kicad_pcb
	(version 20260206)
	(generator "pcbnew")
	(generator_version "10.0")
	(general
		(thickness 1.6)
		(legacy_teardrops no)
	)
	(paper "A4")
	(title_block
		(title "04192023_DAF0TMB3IC0_F0TG_MB_C_brd_V02_OCP.brd")
		(comment 1 "Grand Teton / footprints 5795-5797 of 8354")
	)
	(layers
		(0 "F.Cu" signal "TOP")
		(4 "In1.Cu" signal "GND")
		(6 "In2.Cu" signal "IN1")
		(8 "In3.Cu" signal "GND1")
		(10 "In4.Cu" signal "IN2")
		(12 "In5.Cu" signal "GND2")
		(14 "In6.Cu" signal "IN3")
		(16 "In7.Cu" signal "GND3")
		(18 "In8.Cu" signal "VCC")
		(20 "In9.Cu" signal "VCC1")
		(22 "In10.Cu" signal "GND4")
		(24 "In11.Cu" signal "IN4")
		(26 "In12.Cu" signal "GND5")
		(28 "In13.Cu" signal "IN5")
		(30 "In14.Cu" signal "GND6")
		(32 "In15.Cu" signal "IN6")
		(34 "In16.Cu" signal "GND7")
		(2 "B.Cu" signal "BOTTOM")
		(9 "F.Adhes" user "F.Adhesive")
		(11 "B.Adhes" user "B.Adhesive")
		(13 "F.Paste" user "Package Geometry/Pastemask Top")
		(15 "B.Paste" user "Package Geometry/Pastemask Bottom")
		(5 "F.SilkS" user "Ref Des/Silkscreen Top")
		(7 "B.SilkS" user "Ref Des/Silkscreen Bottom")
		(1 "F.Mask" user "Board Geometry/Soldermask Top")
		(3 "B.Mask" user "Board Geometry/Soldermask Bottom")
		(17 "Dwgs.User" user "User.Drawings")
		(19 "Cmts.User" user "User.Comments")
		(21 "Eco1.User" user "User.Eco1")
		(23 "Eco2.User" user "User.Eco2")
		(25 "Edge.Cuts" user "Board Geometry/Outline")
		(27 "Margin" user)
		(31 "F.CrtYd" user "Package Geometry/Place Bound Top")
		(29 "B.CrtYd" user "Package Geometry/Place Bound Bottom")
		(35 "F.Fab" user "Ref Des/Assembly Top")
		(33 "B.Fab" user "Ref Des/Assembly Bottom")
	)
	(footprint ""
		(layer "B.Cu")
		(at 164.325554 -349.228156)
		(property "Reference" "PR6"
			(at 0 0 0)
			(layer "B.SilkS")
			(hide yes)
			(effects
				(font
					(size 1.27 1.27)
				)
				(justify mirror)
			)
		)
		(property "Value" ""
			(at 0 0 0)
			(layer "B.Fab")
			(effects
				(font
					(size 1.27 1.27)
				)
				(justify mirror)
			)
		)
		(duplicate_pad_numbers_are_jumpers no)
		(fp_line
			(start -0.7874 -0.4064)
			(end -0.7874 0.4064)
			(stroke
				(width 0.1524)
				(type default)
			)
			(layer "B.SilkS")
		)
		(fp_line
			(start -0.7874 0.4064)
			(end 0.7874 0.4064)
			(stroke
				(width 0.1524)
				(type default)
			)
			(layer "B.SilkS")
		)
		(fp_line
			(start 0.7874 -0.4064)
			(end -0.7874 -0.4064)
			(stroke
				(width 0.1524)
				(type default)
			)
			(layer "B.SilkS")
		)
		(fp_line
			(start 0.7874 0.4064)
			(end 0.7874 -0.4064)
			(stroke
				(width 0.1524)
				(type default)
			)
			(layer "B.SilkS")
		)
		(fp_line
			(start -0.67945 -0.3048)
			(end -0.67945 0.3048)
			(stroke
				(width 0.1)
				(type default)
			)
			(layer "B.Fab")
		)
		(fp_line
			(start -0.67945 0.3048)
			(end -0.120396 0.3048)
			(stroke
				(width 0.1)
				(type default)
			)
			(layer "B.Fab")
		)
		(fp_line
			(start -0.12065 -0.3048)
			(end -0.67945 -0.3048)
			(stroke
				(width 0.1)
				(type default)
			)
			(layer "B.Fab")
		)
		(fp_line
			(start -0.12065 -0.2794)
			(end -0.12065 -0.3048)
			(stroke
				(width 0.1)
				(type default)
			)
			(layer "B.Fab")
		)
		(fp_line
			(start -0.120396 0.2794)
			(end 0.12065 0.2794)
			(stroke
				(width 0.1)
				(type default)
			)
			(layer "B.Fab")
		)
		(fp_line
			(start -0.120396 0.3048)
			(end -0.120396 0.2794)
			(stroke
				(width 0.1)
				(type default)
			)
			(layer "B.Fab")
		)
		(fp_line
			(start 0.12065 -0.305054)
			(end 0.12065 -0.2794)
			(stroke
				(width 0.1)
				(type default)
			)
			(layer "B.Fab")
		)
		(fp_line
			(start 0.12065 -0.2794)
			(end -0.12065 -0.2794)
			(stroke
				(width 0.1)
				(type default)
			)
			(layer "B.Fab")
		)
		(fp_line
			(start 0.12065 0.2794)
			(end 0.12065 0.3048)
			(stroke
				(width 0.1)
				(type default)
			)
			(layer "B.Fab")
		)
		(fp_line
			(start 0.12065 0.3048)
			(end 0.67945 0.3048)
			(stroke
				(width 0.1)
				(type default)
			)
			(layer "B.Fab")
		)
		(fp_line
			(start 0.67945 -0.305054)
			(end 0.12065 -0.305054)
			(stroke
				(width 0.1)
				(type default)
			)
			(layer "B.Fab")
		)
		(fp_line
			(start 0.67945 0.3048)
			(end 0.67945 -0.305054)
			(stroke
				(width 0.1)
				(type default)
			)
			(layer "B.Fab")
		)
		(pad "1" smd circle
			(at 0.40005 0 180)
			(size 0 0)
			(layers "B.Cu" "B.Mask" "B.Paste")
			(net "PVDD11_S3_P1_VMON")
		)
		(pad "2" smd circle
			(at -0.40005 0 180)
			(size 0 0)
			(layers "B.Cu" "B.Mask" "B.Paste")
			(net "GND")
		)
	)
	(footprint ""
		(layer "B.Cu")
		(at 315.585094 -41.13784 90)
		(property "Reference" "R3942"
			(at 0 0 90)
			(layer "B.SilkS")
			(hide yes)
			(effects
				(font
					(size 1.27 1.27)
				)
				(justify mirror)
			)
		)
		(property "Value" ""
			(at 0 0 90)
			(layer "B.Fab")
			(effects
				(font
					(size 1.27 1.27)
				)
				(justify mirror)
			)
		)
		(duplicate_pad_numbers_are_jumpers no)
		(fp_line
			(start 0.7874 -0.4064)
			(end -0.7874 -0.4064)
			(stroke
				(width 0.1524)
				(type default)
			)
			(layer "B.SilkS")
		)
		(fp_line
			(start -0.7874 -0.4064)
			(end -0.7874 0.4064)
			(stroke
				(width 0.1524)
				(type default)
			)
			(layer "B.SilkS")
		)
		(fp_line
			(start 0.7874 0.4064)
			(end 0.7874 -0.4064)
			(stroke
				(width 0.1524)
				(type default)
			)
			(layer "B.SilkS")
		)
		(fp_line
			(start -0.7874 0.4064)
			(end 0.7874 0.4064)
			(stroke
				(width 0.1524)
				(type default)
			)
			(layer "B.SilkS")
		)
		(fp_line
			(start 0.67945 -0.305054)
			(end 0.12065 -0.305054)
			(stroke
				(width 0.1)
				(type default)
			)
			(layer "B.Fab")
		)
		(fp_line
			(start 0.12065 -0.305054)
			(end 0.12065 -0.2794)
			(stroke
				(width 0.1)
				(type default)
			)
			(layer "B.Fab")
		)
		(fp_line
			(start -0.12065 -0.3048)
			(end -0.67945 -0.3048)
			(stroke
				(width 0.1)
				(type default)
			)
			(layer "B.Fab")
		)
		(fp_line
			(start -0.67945 -0.3048)
			(end -0.67945 0.3048)
			(stroke
				(width 0.1)
				(type default)
			)
			(layer "B.Fab")
		)
		(fp_line
			(start 0.12065 -0.2794)
			(end -0.12065 -0.2794)
			(stroke
				(width 0.1)
				(type default)
			)
			(layer "B.Fab")
		)
		(fp_line
			(start -0.12065 -0.2794)
			(end -0.12065 -0.3048)
			(stroke
				(width 0.1)
				(type default)
			)
			(layer "B.Fab")
		)
		(fp_line
			(start 0.12065 0.2794)
			(end 0.12065 0.3048)
			(stroke
				(width 0.1)
				(type default)
			)
			(layer "B.Fab")
		)
		(fp_line
			(start -0.120396 0.2794)
			(end 0.12065 0.2794)
			(stroke
				(width 0.1)
				(type default)
			)
			(layer "B.Fab")
		)
		(fp_line
			(start 0.67945 0.3048)
			(end 0.67945 -0.305054)
			(stroke
				(width 0.1)
				(type default)
			)
			(layer "B.Fab")
		)
		(fp_line
			(start 0.12065 0.3048)
			(end 0.67945 0.3048)
			(stroke
				(width 0.1)
				(type default)
			)
			(layer "B.Fab")
		)
		(fp_line
			(start -0.120396 0.3048)
			(end -0.120396 0.2794)
			(stroke
				(width 0.1)
				(type default)
			)
			(layer "B.Fab")
		)
		(fp_line
			(start -0.67945 0.3048)
			(end -0.120396 0.3048)
			(stroke
				(width 0.1)
				(type default)
			)
			(layer "B.Fab")
		)
		(pad "1" smd rect
			(at 0.40005 0 90)
			(size 0.4572 0.508)
			(layers "B.Cu" "B.Mask" "B.Paste")
			(net "P12V_E1S_0_ISENSE_MPS_TIC")
		)
		(pad "2" smd rect
			(at -0.40005 0 90)
			(size 0.4572 0.508)
			(layers "B.Cu" "B.Mask" "B.Paste")
			(net "P12V_E1S_0_ISENSE_TIC")
		)
	)
	(footprint ""
		(layer "B.Cu")
		(at 152.202642 -76.72324)
		(property "Reference" "PC850"
			(at 0 0 0)
			(layer "B.SilkS")
			(hide yes)
			(effects
				(font
					(size 1.27 1.27)
				)
				(justify mirror)
			)
		)
		(property "Value" ""
			(at 0 0 0)
			(layer "B.Fab")
			(effects
				(font
					(size 1.27 1.27)
				)
				(justify mirror)
			)
		)
		(duplicate_pad_numbers_are_jumpers no)
		(fp_line
			(start -1.524 -0.762)
			(end -1.524 0.762)
			(stroke
				(width 0.1524)
				(type default)
			)
			(layer "B.SilkS")
		)
		(fp_line
			(start -1.524 0.762)
			(end 1.524 0.762)
			(stroke
				(width 0.1524)
				(type default)
			)
			(layer "B.SilkS")
		)
		(fp_line
			(start 1.524 -0.762)
			(end -1.524 -0.762)
			(stroke
				(width 0.1524)
				(type default)
			)
			(layer "B.SilkS")
		)
		(fp_line
			(start 1.524 0.762)
			(end 1.524 -0.762)
			(stroke
				(width 0.1524)
				(type default)
			)
			(layer "B.SilkS")
		)
		(fp_line
			(start -1.1049 -0.724916)
			(end 1.1049 -0.724916)
			(stroke
				(width 0.1)
				(type default)
			)
			(layer "B.Fab")
		)
		(fp_line
			(start -1.1049 0.724916)
			(end -1.1049 -0.724916)
			(stroke
				(width 0.1)
				(type default)
			)
			(layer "B.Fab")
		)
		(fp_line
			(start 1.1049 -0.724916)
			(end 1.1049 0.724916)
			(stroke
				(width 0.1)
				(type default)
			)
			(layer "B.Fab")
		)
		(fp_line
			(start 1.1049 0.724916)
			(end -1.1049 0.724916)
			(stroke
				(width 0.1)
				(type default)
			)
			(layer "B.Fab")
		)
		(pad "1" smd rect
			(at 0.889 0)
			(size 1.016 1.27)
			(layers "B.Cu" "B.Mask" "B.Paste")
			(net "P1V8_AUX")
		)
		(pad "2" smd rect
			(at -0.889 0)
			(size 1.016 1.27)
			(layers "B.Cu" "B.Mask" "B.Paste")
			(net "GND")
		)
	)
)
